(kicad_pcb
	(version 20260206)
	(generator "pcbnew")
	(generator_version "10.0")
	(general
		(thickness 1.6)
		(legacy_teardrops no)
	)
	(paper "A4")
	(title_block
		(title "01162023_DA0F0TEBIF0_F0T_Expander_BD_F_brd_V02_OCP.brd")
		(comment 1 "Grand Teton / footprints 7345-7352 of 9728")
	)
	(layers
		(0 "F.Cu" signal "TOP")
		(4 "In1.Cu" signal "GND")
		(6 "In2.Cu" signal "VCC")
		(8 "In3.Cu" signal "VCC1")
		(10 "In4.Cu" signal "GND1")
		(12 "In5.Cu" signal "IN1")
		(14 "In6.Cu" signal "GND2")
		(16 "In7.Cu" signal "IN2")
		(18 "In8.Cu" signal "GND3")
		(20 "In9.Cu" signal "IN3")
		(22 "In10.Cu" signal "GND4")
		(24 "In11.Cu" signal "IN4")
		(26 "In12.Cu" signal "GND5")
		(28 "In13.Cu" signal "IN5")
		(30 "In14.Cu" signal "GND6")
		(32 "In15.Cu" signal "IN6")
		(34 "In16.Cu" signal "GND7")
		(2 "B.Cu" signal "BOTTOM")
		(9 "F.Adhes" user "F.Adhesive")
		(11 "B.Adhes" user "B.Adhesive")
		(13 "F.Paste" user "Package Geometry/Pastemask Top")
		(15 "B.Paste" user "Package Geometry/Pastemask Bottom")
		(5 "F.SilkS" user "Ref Des/Silkscreen Top")
		(7 "B.SilkS" user "Ref Des/Silkscreen Bottom")
		(1 "F.Mask" user "Board Geometry/Soldermask Top")
		(3 "B.Mask" user "Board Geometry/Soldermask Bottom")
		(17 "Dwgs.User" user "User.Drawings")
		(19 "Cmts.User" user "User.Comments")
		(21 "Eco1.User" user "User.Eco1")
		(23 "Eco2.User" user "User.Eco2")
		(25 "Edge.Cuts" user "Board Geometry/Outline")
		(27 "Margin" user)
		(31 "F.CrtYd" user "Package Geometry/Place Bound Top")
		(29 "B.CrtYd" user "Package Geometry/Place Bound Bottom")
		(35 "F.Fab" user "Ref Des/Assembly Top")
		(33 "B.Fab" user "Ref Des/Assembly Bottom")
	)
	(footprint ""
		(layer "B.Cu")
		(at 209.67446 -225.671888 90)
		(property "Reference" "R6817"
			(at 0 0 90)
			(layer "B.SilkS")
			(hide yes)
			(effects
				(font
					(size 1.27 1.27)
				)
				(justify mirror)
			)
		)
		(property "Value" ""
			(at 0 0 90)
			(layer "B.Fab")
			(effects
				(font
					(size 1.27 1.27)
				)
				(justify mirror)
			)
		)
		(duplicate_pad_numbers_are_jumpers no)
		(fp_line
			(start 0.7874 -0.4064)
			(end -0.7874 -0.4064)
			(stroke
				(width 0.1524)
				(type default)
			)
			(layer "B.SilkS")
		)
		(fp_line
			(start -0.7874 -0.4064)
			(end -0.7874 0.4064)
			(stroke
				(width 0.1524)
				(type default)
			)
			(layer "B.SilkS")
		)
		(fp_line
			(start 0.7874 0.4064)
			(end 0.7874 -0.4064)
			(stroke
				(width 0.1524)
				(type default)
			)
			(layer "B.SilkS")
		)
		(fp_line
			(start -0.7874 0.4064)
			(end 0.7874 0.4064)
			(stroke
				(width 0.1524)
				(type default)
			)
			(layer "B.SilkS")
		)
		(fp_line
			(start 0.67945 -0.305054)
			(end 0.12065 -0.305054)
			(stroke
				(width 0.1)
				(type default)
			)
			(layer "B.Fab")
		)
		(fp_line
			(start 0.12065 -0.305054)
			(end 0.12065 -0.2794)
			(stroke
				(width 0.1)
				(type default)
			)
			(layer "B.Fab")
		)
		(fp_line
			(start -0.12065 -0.3048)
			(end -0.67945 -0.3048)
			(stroke
				(width 0.1)
				(type default)
			)
			(layer "B.Fab")
		)
		(fp_line
			(start -0.67945 -0.3048)
			(end -0.67945 0.3048)
			(stroke
				(width 0.1)
				(type default)
			)
			(layer "B.Fab")
		)
		(fp_line
			(start 0.12065 -0.2794)
			(end -0.12065 -0.2794)
			(stroke
				(width 0.1)
				(type default)
			)
			(layer "B.Fab")
		)
		(fp_line
			(start -0.12065 -0.2794)
			(end -0.12065 -0.3048)
			(stroke
				(width 0.1)
				(type default)
			)
			(layer "B.Fab")
		)
		(fp_line
			(start 0.12065 0.2794)
			(end 0.12065 0.3048)
			(stroke
				(width 0.1)
				(type default)
			)
			(layer "B.Fab")
		)
		(fp_line
			(start -0.120396 0.2794)
			(end 0.12065 0.2794)
			(stroke
				(width 0.1)
				(type default)
			)
			(layer "B.Fab")
		)
		(fp_line
			(start 0.67945 0.3048)
			(end 0.67945 -0.305054)
			(stroke
				(width 0.1)
				(type default)
			)
			(layer "B.Fab")
		)
		(fp_line
			(start 0.12065 0.3048)
			(end 0.67945 0.3048)
			(stroke
				(width 0.1)
				(type default)
			)
			(layer "B.Fab")
		)
		(fp_line
			(start -0.120396 0.3048)
			(end -0.120396 0.2794)
			(stroke
				(width 0.1)
				(type default)
			)
			(layer "B.Fab")
		)
		(fp_line
			(start -0.67945 0.3048)
			(end -0.120396 0.3048)
			(stroke
				(width 0.1)
				(type default)
			)
			(layer "B.Fab")
		)
		(pad "1" smd circle
			(at 0.40005 0 270)
			(size 0 0)
			(layers "B.Cu" "B.Mask" "B.Paste")
			(net "GND")
		)
		(pad "2" smd circle
			(at -0.40005 0 270)
			(size 0 0)
			(layers "B.Cu" "B.Mask" "B.Paste")
			(net "ADC_TYPE_ADC_R")
		)
	)
	(footprint ""
		(layer "B.Cu")
		(at 360.540554 -321.831716 -90)
		(property "Reference" "R6548"
			(at 0 0 90)
			(layer "B.SilkS")
			(hide yes)
			(effects
				(font
					(size 1.27 1.27)
				)
				(justify mirror)
			)
		)
		(property "Value" ""
			(at 0 0 90)
			(layer "B.Fab")
			(effects
				(font
					(size 1.27 1.27)
				)
				(justify mirror)
			)
		)
		(duplicate_pad_numbers_are_jumpers no)
		(fp_line
			(start -0.7874 0.4064)
			(end 0.7874 0.4064)
			(stroke
				(width 0.1524)
				(type default)
			)
			(layer "B.SilkS")
		)
		(fp_line
			(start 0.7874 0.4064)
			(end 0.7874 -0.4064)
			(stroke
				(width 0.1524)
				(type default)
			)
			(layer "B.SilkS")
		)
		(fp_line
			(start -0.7874 -0.4064)
			(end -0.7874 0.4064)
			(stroke
				(width 0.1524)
				(type default)
			)
			(layer "B.SilkS")
		)
		(fp_line
			(start 0.7874 -0.4064)
			(end -0.7874 -0.4064)
			(stroke
				(width 0.1524)
				(type default)
			)
			(layer "B.SilkS")
		)
		(fp_line
			(start -0.67945 0.3048)
			(end -0.120396 0.3048)
			(stroke
				(width 0.1)
				(type default)
			)
			(layer "B.Fab")
		)
		(fp_line
			(start -0.120396 0.3048)
			(end -0.120396 0.2794)
			(stroke
				(width 0.1)
				(type default)
			)
			(layer "B.Fab")
		)
		(fp_line
			(start 0.12065 0.3048)
			(end 0.67945 0.3048)
			(stroke
				(width 0.1)
				(type default)
			)
			(layer "B.Fab")
		)
		(fp_line
			(start 0.67945 0.3048)
			(end 0.67945 -0.305054)
			(stroke
				(width 0.1)
				(type default)
			)
			(layer "B.Fab")
		)
		(fp_line
			(start -0.120396 0.2794)
			(end 0.12065 0.2794)
			(stroke
				(width 0.1)
				(type default)
			)
			(layer "B.Fab")
		)
		(fp_line
			(start 0.12065 0.2794)
			(end 0.12065 0.3048)
			(stroke
				(width 0.1)
				(type default)
			)
			(layer "B.Fab")
		)
		(fp_line
			(start -0.12065 -0.2794)
			(end -0.12065 -0.3048)
			(stroke
				(width 0.1)
				(type default)
			)
			(layer "B.Fab")
		)
		(fp_line
			(start 0.12065 -0.2794)
			(end -0.12065 -0.2794)
			(stroke
				(width 0.1)
				(type default)
			)
			(layer "B.Fab")
		)
		(fp_line
			(start -0.67945 -0.3048)
			(end -0.67945 0.3048)
			(stroke
				(width 0.1)
				(type default)
			)
			(layer "B.Fab")
		)
		(fp_line
			(start -0.12065 -0.3048)
			(end -0.67945 -0.3048)
			(stroke
				(width 0.1)
				(type default)
			)
			(layer "B.Fab")
		)
		(fp_line
			(start 0.12065 -0.305054)
			(end 0.12065 -0.2794)
			(stroke
				(width 0.1)
				(type default)
			)
			(layer "B.Fab")
		)
		(fp_line
			(start 0.67945 -0.305054)
			(end 0.12065 -0.305054)
			(stroke
				(width 0.1)
				(type default)
			)
			(layer "B.Fab")
		)
		(pad "1" smd circle
			(at 0.40005 0 90)
			(size 0 0)
			(layers "B.Cu" "B.Mask" "B.Paste")
			(net "P0V8_SERDES_VDDA_PEX3")
		)
		(pad "2" smd circle
			(at -0.40005 0 90)
			(size 0 0)
			(layers "B.Cu" "B.Mask" "B.Paste")
			(net "P0V8_SERDES_VDDA_PEX3_C11")
		)
	)
	(footprint ""
		(layer "B.Cu")
		(at 177.423826 -194.683634)
		(property "Reference" "R1035"
			(at 0 0 0)
			(layer "B.SilkS")
			(hide yes)
			(effects
				(font
					(size 1.27 1.27)
				)
				(justify mirror)
			)
		)
		(property "Value" ""
			(at 0 0 0)
			(layer "B.Fab")
			(effects
				(font
					(size 1.27 1.27)
				)
				(justify mirror)
			)
		)
		(duplicate_pad_numbers_are_jumpers no)
		(fp_line
			(start -0.7874 -0.4064)
			(end -0.7874 0.4064)
			(stroke
				(width 0.1524)
				(type default)
			)
			(layer "B.SilkS")
		)
		(fp_line
			(start -0.7874 0.4064)
			(end 0.7874 0.4064)
			(stroke
				(width 0.1524)
				(type default)
			)
			(layer "B.SilkS")
		)
		(fp_line
			(start 0.7874 -0.4064)
			(end -0.7874 -0.4064)
			(stroke
				(width 0.1524)
				(type default)
			)
			(layer "B.SilkS")
		)
		(fp_line
			(start 0.7874 0.4064)
			(end 0.7874 -0.4064)
			(stroke
				(width 0.1524)
				(type default)
			)
			(layer "B.SilkS")
		)
		(fp_line
			(start -0.67945 -0.3048)
			(end -0.67945 0.3048)
			(stroke
				(width 0.1)
				(type default)
			)
			(layer "B.Fab")
		)
		(fp_line
			(start -0.67945 0.3048)
			(end -0.120396 0.3048)
			(stroke
				(width 0.1)
				(type default)
			)
			(layer "B.Fab")
		)
		(fp_line
			(start -0.12065 -0.3048)
			(end -0.67945 -0.3048)
			(stroke
				(width 0.1)
				(type default)
			)
			(layer "B.Fab")
		)
		(fp_line
			(start -0.12065 -0.2794)
			(end -0.12065 -0.3048)
			(stroke
				(width 0.1)
				(type default)
			)
			(layer "B.Fab")
		)
		(fp_line
			(start -0.120396 0.2794)
			(end 0.12065 0.2794)
			(stroke
				(width 0.1)
				(type default)
			)
			(layer "B.Fab")
		)
		(fp_line
			(start -0.120396 0.3048)
			(end -0.120396 0.2794)
			(stroke
				(width 0.1)
				(type default)
			)
			(layer "B.Fab")
		)
		(fp_line
			(start 0.12065 -0.305054)
			(end 0.12065 -0.2794)
			(stroke
				(width 0.1)
				(type default)
			)
			(layer "B.Fab")
		)
		(fp_line
			(start 0.12065 -0.2794)
			(end -0.12065 -0.2794)
			(stroke
				(width 0.1)
				(type default)
			)
			(layer "B.Fab")
		)
		(fp_line
			(start 0.12065 0.2794)
			(end 0.12065 0.3048)
			(stroke
				(width 0.1)
				(type default)
			)
			(layer "B.Fab")
		)
		(fp_line
			(start 0.12065 0.3048)
			(end 0.67945 0.3048)
			(stroke
				(width 0.1)
				(type default)
			)
			(layer "B.Fab")
		)
		(fp_line
			(start 0.67945 -0.305054)
			(end 0.12065 -0.305054)
			(stroke
				(width 0.1)
				(type default)
			)
			(layer "B.Fab")
		)
		(fp_line
			(start 0.67945 0.3048)
			(end 0.67945 -0.305054)
			(stroke
				(width 0.1)
				(type default)
			)
			(layer "B.Fab")
		)
		(pad "1" smd circle
			(at 0.40005 0 180)
			(size 0 0)
			(layers "B.Cu" "B.Mask" "B.Paste")
			(net "GND")
		)
		(pad "2" smd circle
			(at -0.40005 0 180)
			(size 0 0)
			(layers "B.Cu" "B.Mask" "B.Paste")
			(net "SPI_BIC1_MOSI_LS01_DIR3")
		)
	)
	(footprint ""
		(layer "B.Cu")
		(at 51.574954 -297.79976 90)
		(property "Reference" "C1140"
			(at 0 0 90)
			(layer "B.SilkS")
			(hide yes)
			(effects
				(font
					(size 1.27 1.27)
				)
				(justify mirror)
			)
		)
		(property "Value" ""
			(at 0 0 90)
			(layer "B.Fab")
			(effects
				(font
					(size 1.27 1.27)
				)
				(justify mirror)
			)
		)
		(duplicate_pad_numbers_are_jumpers no)
		(fp_line
			(start 0.299974 -0.150114)
			(end -0.299974 -0.150114)
			(stroke
				(width 0.1)
				(type default)
			)
			(layer "B.Fab")
		)
		(fp_line
			(start -0.299974 -0.150114)
			(end -0.299974 0.150114)
			(stroke
				(width 0.1)
				(type default)
			)
			(layer "B.Fab")
		)
		(fp_line
			(start 0.299974 0.150114)
			(end 0.299974 -0.150114)
			(stroke
				(width 0.1)
				(type default)
			)
			(layer "B.Fab")
		)
		(fp_line
			(start -0.299974 0.150114)
			(end 0.299974 0.150114)
			(stroke
				(width 0.1)
				(type default)
			)
			(layer "B.Fab")
		)
		(pad "1" smd rect
			(at 0.2667 0 270)
			(size 0.3048 0.381)
			(layers "B.Cu" "B.Mask" "B.Paste")
			(net "P0V8_PEX0")
		)
		(pad "2" smd rect
			(at -0.2667 0 270)
			(size 0.3048 0.381)
			(layers "B.Cu" "B.Mask" "B.Paste")
			(net "GND")
		)
	)
	(footprint ""
		(layer "B.Cu")
		(at 416.499802 -298.27474 180)
		(property "Reference" "C1890"
			(at 0 0 0)
			(layer "B.SilkS")
			(hide yes)
			(effects
				(font
					(size 1.27 1.27)
				)
				(justify mirror)
			)
		)
		(property "Value" ""
			(at 0 0 0)
			(layer "B.Fab")
			(effects
				(font
					(size 1.27 1.27)
				)
				(justify mirror)
			)
		)
		(duplicate_pad_numbers_are_jumpers no)
		(fp_line
			(start 0.299974 0.150114)
			(end 0.299974 -0.150114)
			(stroke
				(width 0.1)
				(type default)
			)
			(layer "B.Fab")
		)
		(fp_line
			(start 0.299974 -0.150114)
			(end -0.299974 -0.150114)
			(stroke
				(width 0.1)
				(type default)
			)
			(layer "B.Fab")
		)
		(fp_line
			(start -0.299974 0.150114)
			(end 0.299974 0.150114)
			(stroke
				(width 0.1)
				(type default)
			)
			(layer "B.Fab")
		)
		(fp_line
			(start -0.299974 -0.150114)
			(end -0.299974 0.150114)
			(stroke
				(width 0.1)
				(type default)
			)
			(layer "B.Fab")
		)
		(pad "1" smd rect
			(at 0.2667 0)
			(size 0.3048 0.381)
			(layers "B.Cu" "B.Mask" "B.Paste")
			(net "P0V8_PEX3")
		)
		(pad "2" smd rect
			(at -0.2667 0)
			(size 0.3048 0.381)
			(layers "B.Cu" "B.Mask" "B.Paste")
			(net "GND")
		)
	)
	(footprint ""
		(layer "B.Cu")
		(at 198.549768 -366.339628)
		(property "Reference" "PC8"
			(at 0 0 0)
			(layer "B.SilkS")
			(hide yes)
			(effects
				(font
					(size 1.27 1.27)
				)
				(justify mirror)
			)
		)
		(property "Value" ""
			(at 0 0 0)
			(layer "B.Fab")
			(effects
				(font
					(size 1.27 1.27)
				)
				(justify mirror)
			)
		)
		(duplicate_pad_numbers_are_jumpers no)
		(fp_line
			(start -0.7874 -0.4064)
			(end -0.7874 0.4064)
			(stroke
				(width 0.1524)
				(type default)
			)
			(layer "B.SilkS")
		)
		(fp_line
			(start -0.7874 0.4064)
			(end 0.7874 0.4064)
			(stroke
				(width 0.1524)
				(type default)
			)
			(layer "B.SilkS")
		)
		(fp_line
			(start 0.7874 -0.4064)
			(end -0.7874 -0.4064)
			(stroke
				(width 0.1524)
				(type default)
			)
			(layer "B.SilkS")
		)
		(fp_line
			(start 0.7874 0.4064)
			(end 0.7874 -0.4064)
			(stroke
				(width 0.1524)
				(type default)
			)
			(layer "B.SilkS")
		)
		(fp_line
			(start -0.67945 -0.3048)
			(end -0.67945 0.3048)
			(stroke
				(width 0.1)
				(type default)
			)
			(layer "B.Fab")
		)
		(fp_line
			(start -0.67945 0.3048)
			(end -0.120396 0.3048)
			(stroke
				(width 0.1)
				(type default)
			)
			(layer "B.Fab")
		)
		(fp_line
			(start -0.12065 -0.3048)
			(end -0.67945 -0.3048)
			(stroke
				(width 0.1)
				(type default)
			)
			(layer "B.Fab")
		)
		(fp_line
			(start -0.12065 -0.2794)
			(end -0.12065 -0.3048)
			(stroke
				(width 0.1)
				(type default)
			)
			(layer "B.Fab")
		)
		(fp_line
			(start -0.120396 0.2794)
			(end 0.12065 0.2794)
			(stroke
				(width 0.1)
				(type default)
			)
			(layer "B.Fab")
		)
		(fp_line
			(start -0.120396 0.3048)
			(end -0.120396 0.2794)
			(stroke
				(width 0.1)
				(type default)
			)
			(layer "B.Fab")
		)
		(fp_line
			(start 0.12065 -0.305054)
			(end 0.12065 -0.2794)
			(stroke
				(width 0.1)
				(type default)
			)
			(layer "B.Fab")
		)
		(fp_line
			(start 0.12065 -0.2794)
			(end -0.12065 -0.2794)
			(stroke
				(width 0.1)
				(type default)
			)
			(layer "B.Fab")
		)
		(fp_line
			(start 0.12065 0.2794)
			(end 0.12065 0.3048)
			(stroke
				(width 0.1)
				(type default)
			)
			(layer "B.Fab")
		)
		(fp_line
			(start 0.12065 0.3048)
			(end 0.67945 0.3048)
			(stroke
				(width 0.1)
				(type default)
			)
			(layer "B.Fab")
		)
		(fp_line
			(start 0.67945 -0.305054)
			(end 0.12065 -0.305054)
			(stroke
				(width 0.1)
				(type default)
			)
			(layer "B.Fab")
		)
		(fp_line
			(start 0.67945 0.3048)
			(end 0.67945 -0.305054)
			(stroke
				(width 0.1)
				(type default)
			)
			(layer "B.Fab")
		)
		(pad "1" smd circle
			(at 0.40005 0 180)
			(size 0 0)
			(layers "B.Cu" "B.Mask" "B.Paste")
			(net "HSC_SS")
		)
		(pad "2" smd circle
			(at -0.40005 0 180)
			(size 0 0)
			(layers "B.Cu" "B.Mask" "B.Paste")
			(net "AGND_HSC")
		)
	)
	(footprint ""
		(layer "B.Cu")
		(at 461.729328 -307.589428 90)
		(property "Reference" "R4438"
			(at 0 0 90)
			(layer "B.SilkS")
			(hide yes)
			(effects
				(font
					(size 1.27 1.27)
				)
				(justify mirror)
			)
		)
		(property "Value" ""
			(at 0 0 90)
			(layer "B.Fab")
			(effects
				(font
					(size 1.27 1.27)
				)
				(justify mirror)
			)
		)
		(duplicate_pad_numbers_are_jumpers no)
		(fp_line
			(start 0.7874 -0.4064)
			(end -0.7874 -0.4064)
			(stroke
				(width 0.1524)
				(type default)
			)
			(layer "B.SilkS")
		)
		(fp_line
			(start -0.7874 -0.4064)
			(end -0.7874 0.4064)
			(stroke
				(width 0.1524)
				(type default)
			)
			(layer "B.SilkS")
		)
		(fp_line
			(start 0.7874 0.4064)
			(end 0.7874 -0.4064)
			(stroke
				(width 0.1524)
				(type default)
			)
			(layer "B.SilkS")
		)
		(fp_line
			(start -0.7874 0.4064)
			(end 0.7874 0.4064)
			(stroke
				(width 0.1524)
				(type default)
			)
			(layer "B.SilkS")
		)
		(fp_line
			(start 0.67945 -0.305054)
			(end 0.12065 -0.305054)
			(stroke
				(width 0.1)
				(type default)
			)
			(layer "B.Fab")
		)
		(fp_line
			(start 0.12065 -0.305054)
			(end 0.12065 -0.2794)
			(stroke
				(width 0.1)
				(type default)
			)
			(layer "B.Fab")
		)
		(fp_line
			(start -0.12065 -0.3048)
			(end -0.67945 -0.3048)
			(stroke
				(width 0.1)
				(type default)
			)
			(layer "B.Fab")
		)
		(fp_line
			(start -0.67945 -0.3048)
			(end -0.67945 0.3048)
			(stroke
				(width 0.1)
				(type default)
			)
			(layer "B.Fab")
		)
		(fp_line
			(start 0.12065 -0.2794)
			(end -0.12065 -0.2794)
			(stroke
				(width 0.1)
				(type default)
			)
			(layer "B.Fab")
		)
		(fp_line
			(start -0.12065 -0.2794)
			(end -0.12065 -0.3048)
			(stroke
				(width 0.1)
				(type default)
			)
			(layer "B.Fab")
		)
		(fp_line
			(start 0.12065 0.2794)
			(end 0.12065 0.3048)
			(stroke
				(width 0.1)
				(type default)
			)
			(layer "B.Fab")
		)
		(fp_line
			(start -0.120396 0.2794)
			(end 0.12065 0.2794)
			(stroke
				(width 0.1)
				(type default)
			)
			(layer "B.Fab")
		)
		(fp_line
			(start 0.67945 0.3048)
			(end 0.67945 -0.305054)
			(stroke
				(width 0.1)
				(type default)
			)
			(layer "B.Fab")
		)
		(fp_line
			(start 0.12065 0.3048)
			(end 0.67945 0.3048)
			(stroke
				(width 0.1)
				(type default)
			)
			(layer "B.Fab")
		)
		(fp_line
			(start -0.120396 0.3048)
			(end -0.120396 0.2794)
			(stroke
				(width 0.1)
				(type default)
			)
			(layer "B.Fab")
		)
		(fp_line
			(start -0.67945 0.3048)
			(end -0.120396 0.3048)
			(stroke
				(width 0.1)
				(type default)
			)
			(layer "B.Fab")
		)
		(pad "1" smd circle
			(at 0.40005 0 270)
			(size 0 0)
			(layers "B.Cu" "B.Mask" "B.Paste")
			(net "PWRGD_P1V25_PEX3_R")
		)
		(pad "2" smd circle
			(at -0.40005 0 270)
			(size 0 0)
			(layers "B.Cu" "B.Mask" "B.Paste")
			(net "PWRGD_P1V25_PEX3")
		)
	)
	(footprint ""
		(layer "B.Cu")
		(at 299.449744 -299.699934 -90)
		(property "Reference" "C1694"
			(at 0 0 90)
			(layer "B.SilkS")
			(hide yes)
			(effects
				(font
					(size 1.27 1.27)
				)
				(justify mirror)
			)
		)
		(property "Value" ""
			(at 0 0 90)
			(layer "B.Fab")
			(effects
				(font
					(size 1.27 1.27)
				)
				(justify mirror)
			)
		)
		(duplicate_pad_numbers_are_jumpers no)
		(fp_line
			(start -0.299974 0.150114)
			(end 0.299974 0.150114)
			(stroke
				(width 0.1)
				(type default)
			)
			(layer "B.Fab")
		)
		(fp_line
			(start 0.299974 0.150114)
			(end 0.299974 -0.150114)
			(stroke
				(width 0.1)
				(type default)
			)
			(layer "B.Fab")
		)
		(fp_line
			(start -0.299974 -0.150114)
			(end -0.299974 0.150114)
			(stroke
				(width 0.1)
				(type default)
			)
			(layer "B.Fab")
		)
		(fp_line
			(start 0.299974 -0.150114)
			(end -0.299974 -0.150114)
			(stroke
				(width 0.1)
				(type default)
			)
			(layer "B.Fab")
		)
		(pad "1" smd rect
			(at 0.2667 0 90)
			(size 0.3048 0.381)
			(layers "B.Cu" "B.Mask" "B.Paste")
			(net "P0V8_SERDES_VDDA_PEX2")
		)
		(pad "2" smd rect
			(at -0.2667 0 90)
			(size 0.3048 0.381)
			(layers "B.Cu" "B.Mask" "B.Paste")
			(net "GND")
		)
	)
)
